(kicad_pcb
	(version 20260206)
	(generator "pcbnew")
	(generator_version "10.0")
	(general
		(thickness 1.6)
		(legacy_teardrops no)
	)
	(paper "A4")
	(title_block
		(title "03242023_DA0F0TMBIJ0_F0T_Motherboard_J_brd_V01_OCP.brd")
		(comment 1 "Grand Teton / footprints 3523-3527 of 6105")
	)
	(layers
		(0 "F.Cu" signal "TOP")
		(4 "In1.Cu" signal "GND")
		(6 "In2.Cu" signal "IN1")
		(8 "In3.Cu" signal "GND1")
		(10 "In4.Cu" signal "IN2")
		(12 "In5.Cu" signal "GND2")
		(14 "In6.Cu" signal "IN3")
		(16 "In7.Cu" signal "GND3")
		(18 "In8.Cu" signal "VCC")
		(20 "In9.Cu" signal "VCC1")
		(22 "In10.Cu" signal "GND4")
		(24 "In11.Cu" signal "IN4")
		(26 "In12.Cu" signal "GND5")
		(28 "In13.Cu" signal "IN5")
		(30 "In14.Cu" signal "GND6")
		(32 "In15.Cu" signal "IN6")
		(34 "In16.Cu" signal "GND7")
		(2 "B.Cu" signal "BOTTOM")
		(9 "F.Adhes" user "F.Adhesive")
		(11 "B.Adhes" user "B.Adhesive")
		(13 "F.Paste" user "Package Geometry/Pastemask Top")
		(15 "B.Paste" user "Package Geometry/Pastemask Bottom")
		(5 "F.SilkS" user "Ref Des/Silkscreen Top")
		(7 "B.SilkS" user "Ref Des/Silkscreen Bottom")
		(1 "F.Mask" user "Board Geometry/Soldermask Top")
		(3 "B.Mask" user "Board Geometry/Soldermask Bottom")
		(17 "Dwgs.User" user "User.Drawings")
		(19 "Cmts.User" user "User.Comments")
		(21 "Eco1.User" user "User.Eco1")
		(23 "Eco2.User" user "User.Eco2")
		(25 "Edge.Cuts" user "Board Geometry/Outline")
		(27 "Margin" user)
		(31 "F.CrtYd" user "Package Geometry/Place Bound Top")
		(29 "B.CrtYd" user "Package Geometry/Place Bound Bottom")
		(35 "F.Fab" user "Ref Des/Assembly Top")
		(33 "B.Fab" user "Ref Des/Assembly Bottom")
	)
	(footprint ""
		(layer "F.Cu")
		(at 412.585662 -364.563914 90)
		(property "Reference" "PC600"
			(at 0 0 90)
			(layer "F.SilkS")
			(hide yes)
			(effects
				(font
					(size 1.27 1.27)
				)
			)
		)
		(property "Value" ""
			(at 0 0 90)
			(layer "F.Fab")
			(effects
				(font
					(size 1.27 1.27)
				)
			)
		)
		(duplicate_pad_numbers_are_jumpers no)
		(fp_line
			(start 0.7874 -0.4064)
			(end 0.7874 0.4064)
			(stroke
				(width 0.1524)
				(type default)
			)
			(layer "F.SilkS")
		)
		(fp_line
			(start -0.7874 -0.4064)
			(end 0.7874 -0.4064)
			(stroke
				(width 0.1524)
				(type default)
			)
			(layer "F.SilkS")
		)
		(fp_line
			(start 0.7874 0.4064)
			(end -0.7874 0.4064)
			(stroke
				(width 0.1524)
				(type default)
			)
			(layer "F.SilkS")
		)
		(fp_line
			(start -0.7874 0.4064)
			(end -0.7874 -0.4064)
			(stroke
				(width 0.1524)
				(type default)
			)
			(layer "F.SilkS")
		)
		(fp_line
			(start -0.12065 -0.305054)
			(end -0.12065 -0.2794)
			(stroke
				(width 0.1)
				(type default)
			)
			(layer "F.Fab")
		)
		(fp_line
			(start -0.67945 -0.305054)
			(end -0.12065 -0.305054)
			(stroke
				(width 0.1)
				(type default)
			)
			(layer "F.Fab")
		)
		(fp_line
			(start 0.67945 -0.3048)
			(end 0.67945 0.3048)
			(stroke
				(width 0.1)
				(type default)
			)
			(layer "F.Fab")
		)
		(fp_line
			(start 0.12065 -0.3048)
			(end 0.67945 -0.3048)
			(stroke
				(width 0.1)
				(type default)
			)
			(layer "F.Fab")
		)
		(fp_line
			(start 0.12065 -0.2794)
			(end 0.12065 -0.3048)
			(stroke
				(width 0.1)
				(type default)
			)
			(layer "F.Fab")
		)
		(fp_line
			(start -0.12065 -0.2794)
			(end 0.12065 -0.2794)
			(stroke
				(width 0.1)
				(type default)
			)
			(layer "F.Fab")
		)
		(fp_line
			(start 0.120396 0.2794)
			(end -0.12065 0.2794)
			(stroke
				(width 0.1)
				(type default)
			)
			(layer "F.Fab")
		)
		(fp_line
			(start -0.12065 0.2794)
			(end -0.12065 0.3048)
			(stroke
				(width 0.1)
				(type default)
			)
			(layer "F.Fab")
		)
		(fp_line
			(start 0.67945 0.3048)
			(end 0.120396 0.3048)
			(stroke
				(width 0.1)
				(type default)
			)
			(layer "F.Fab")
		)
		(fp_line
			(start 0.120396 0.3048)
			(end 0.120396 0.2794)
			(stroke
				(width 0.1)
				(type default)
			)
			(layer "F.Fab")
		)
		(fp_line
			(start -0.12065 0.3048)
			(end -0.67945 0.3048)
			(stroke
				(width 0.1)
				(type default)
			)
			(layer "F.Fab")
		)
		(fp_line
			(start -0.67945 0.3048)
			(end -0.67945 -0.305054)
			(stroke
				(width 0.1)
				(type default)
			)
			(layer "F.Fab")
		)
		(pad "1" smd circle
			(at -0.40005 0 90)
			(size 0 0)
			(layers "F.Cu" "F.Mask" "F.Paste")
			(net "PVCCFA_EHV_FIVRA_CPU0_VDD1")
		)
		(pad "2" smd circle
			(at 0.40005 0 90)
			(size 0 0)
			(layers "F.Cu" "F.Mask" "F.Paste")
			(net "GND")
		)
	)
	(footprint ""
		(layer "F.Cu")
		(at 352.301048 -249.320304 -90)
		(property "Reference" "C1030"
			(at 0 0 270)
			(layer "F.SilkS")
			(hide yes)
			(effects
				(font
					(size 1.27 1.27)
				)
			)
		)
		(property "Value" ""
			(at 0 0 270)
			(layer "F.Fab")
			(effects
				(font
					(size 1.27 1.27)
				)
			)
		)
		(duplicate_pad_numbers_are_jumpers no)
		(fp_line
			(start -0.7874 0.4064)
			(end -0.7874 -0.4064)
			(stroke
				(width 0.1524)
				(type default)
			)
			(layer "F.SilkS")
		)
		(fp_line
			(start 0.7874 0.4064)
			(end -0.7874 0.4064)
			(stroke
				(width 0.1524)
				(type default)
			)
			(layer "F.SilkS")
		)
		(fp_line
			(start -0.7874 -0.4064)
			(end 0.7874 -0.4064)
			(stroke
				(width 0.1524)
				(type default)
			)
			(layer "F.SilkS")
		)
		(fp_line
			(start 0.7874 -0.4064)
			(end 0.7874 0.4064)
			(stroke
				(width 0.1524)
				(type default)
			)
			(layer "F.SilkS")
		)
		(fp_line
			(start -0.67945 0.3048)
			(end -0.67945 -0.305054)
			(stroke
				(width 0.1)
				(type default)
			)
			(layer "F.Fab")
		)
		(fp_line
			(start -0.12065 0.3048)
			(end -0.67945 0.3048)
			(stroke
				(width 0.1)
				(type default)
			)
			(layer "F.Fab")
		)
		(fp_line
			(start 0.120396 0.3048)
			(end 0.120396 0.2794)
			(stroke
				(width 0.1)
				(type default)
			)
			(layer "F.Fab")
		)
		(fp_line
			(start 0.67945 0.3048)
			(end 0.120396 0.3048)
			(stroke
				(width 0.1)
				(type default)
			)
			(layer "F.Fab")
		)
		(fp_line
			(start -0.12065 0.2794)
			(end -0.12065 0.3048)
			(stroke
				(width 0.1)
				(type default)
			)
			(layer "F.Fab")
		)
		(fp_line
			(start 0.120396 0.2794)
			(end -0.12065 0.2794)
			(stroke
				(width 0.1)
				(type default)
			)
			(layer "F.Fab")
		)
		(fp_line
			(start -0.12065 -0.2794)
			(end 0.12065 -0.2794)
			(stroke
				(width 0.1)
				(type default)
			)
			(layer "F.Fab")
		)
		(fp_line
			(start 0.12065 -0.2794)
			(end 0.12065 -0.3048)
			(stroke
				(width 0.1)
				(type default)
			)
			(layer "F.Fab")
		)
		(fp_line
			(start 0.12065 -0.3048)
			(end 0.67945 -0.3048)
			(stroke
				(width 0.1)
				(type default)
			)
			(layer "F.Fab")
		)
		(fp_line
			(start 0.67945 -0.3048)
			(end 0.67945 0.3048)
			(stroke
				(width 0.1)
				(type default)
			)
			(layer "F.Fab")
		)
		(fp_line
			(start -0.67945 -0.305054)
			(end -0.12065 -0.305054)
			(stroke
				(width 0.1)
				(type default)
			)
			(layer "F.Fab")
		)
		(fp_line
			(start -0.12065 -0.305054)
			(end -0.12065 -0.2794)
			(stroke
				(width 0.1)
				(type default)
			)
			(layer "F.Fab")
		)
		(pad "1" smd circle
			(at -0.40005 0 270)
			(size 0 0)
			(layers "F.Cu" "F.Mask" "F.Paste")
			(net "PVCCIN_CPU0")
		)
		(pad "2" smd circle
			(at 0.40005 0 270)
			(size 0 0)
			(layers "F.Cu" "F.Mask" "F.Paste")
			(net "GND")
		)
	)
	(footprint ""
		(layer "F.Cu")
		(at 514.718808 -303.6316 90)
		(property "Reference" "X8"
			(at -2.734056 3.043682 90)
			(unlocked yes)
			(layer "F.SilkS")
			(effects
				(font
					(size 0.7874 0.5842)
					(thickness 0.1524)
				)
				(justify left)
			)
		)
		(property "Value" ""
			(at 0 0 90)
			(layer "F.Fab")
			(effects
				(font
					(size 1.27 1.27)
				)
			)
		)
		(property "Device Type" "TP_TDR_4P_FTS_MPKT4_H025P0200_I"
			(at 1.30175 1.27 180)
			(unlocked yes)
			(layer "F.Fab")
			(hide yes)
			(effects
				(font
					(size 0.635 0.4064)
					(thickness 0.1524)
				)
			)
		)
		(property "User Part Number" "TP15"
			(at 1.30175 1.27 180)
			(unlocked yes)
			(layer "Cmts.User")
			(hide yes)
			(effects
				(font
					(size 0.635 0.4064)
					(thickness 0.1524)
				)
			)
		)
		(duplicate_pad_numbers_are_jumpers no)
		(fp_line
			(start 2.54 -1.27)
			(end 0 -1.27)
			(stroke
				(width 0.1524)
				(type default)
			)
			(layer "F.SilkS")
		)
		(fp_line
			(start 0 -1.27)
			(end 0 -0.635)
			(stroke
				(width 0.1524)
				(type default)
			)
			(layer "F.SilkS")
		)
		(fp_line
			(start 2.54 -1.1303)
			(end 2.54 -1.27)
			(stroke
				(width 0.1524)
				(type default)
			)
			(layer "F.SilkS")
		)
		(fp_line
			(start 0 0.635)
			(end 0 1.905)
			(stroke
				(width 0.1524)
				(type default)
			)
			(layer "F.SilkS")
		)
		(fp_line
			(start 2.54 1.4097)
			(end 2.54 1.1303)
			(stroke
				(width 0.1524)
				(type default)
			)
			(layer "F.SilkS")
		)
		(fp_line
			(start 0 3.175)
			(end 0 3.81)
			(stroke
				(width 0.1524)
				(type default)
			)
			(layer "F.SilkS")
		)
		(fp_line
			(start 2.54 3.81)
			(end 2.54 3.6703)
			(stroke
				(width 0.1524)
				(type default)
			)
			(layer "F.SilkS")
		)
		(fp_line
			(start 0 3.81)
			(end 2.54 3.81)
			(stroke
				(width 0.1524)
				(type default)
			)
			(layer "F.SilkS")
		)
		(fp_poly
			(pts
				(xy -0.761746 0) (xy -2.285746 0.762) (xy -2.285746 -0.762)
			)
			(stroke
				(width 0)
				(type default)
			)
			(fill yes)
			(layer "F.SilkS")
		)
		(fp_line
			(start 2.54 -1.27)
			(end 0 -1.27)
			(stroke
				(width 0.1)
				(type default)
			)
			(layer "F.Fab")
		)
		(fp_line
			(start 0 -1.27)
			(end 0 3.81)
			(stroke
				(width 0.1)
				(type default)
			)
			(layer "F.Fab")
		)
		(fp_line
			(start 2.54 3.81)
			(end 2.54 -1.27)
			(stroke
				(width 0.1)
				(type default)
			)
			(layer "F.Fab")
		)
		(fp_line
			(start 0 3.81)
			(end 2.54 3.81)
			(stroke
				(width 0.1)
				(type default)
			)
			(layer "F.Fab")
		)
		(fp_poly
			(pts
				(xy -0.761746 0) (xy -2.285746 -0.762) (xy -2.285746 0.762)
			)
			(stroke
				(width 0)
				(type default)
			)
			(fill yes)
			(layer "F.Fab")
		)
		(pad "1" thru_hole circle
			(at 0 0 90)
			(size 1.0033 1.0033)
			(drill 0.249936)
			(layers "*.Cu" "*.Mask")
			(remove_unused_layers no)
			(net "TDR_DIFF_85_IN1_DN")
			(clearance 0.10795)
			(thermal_gap 0.10795)
			(padstack
				(mode front_inner_back)
				(layer "Inner"
					(shape circle)
					(size 0.8001 0.8001)
					(clearance 0.1524)
				)
				(layer "B.Cu"
					(shape circle)
					(size 1.0033 1.0033)
					(clearance 0.10795)
				)
			)
		)
		(pad "2" thru_hole circle
			(at 2.54 0 90)
			(size 1.9939 1.9939)
			(drill 0.249936)
			(layers "*.Cu" "*.Mask")
			(remove_unused_layers no)
			(net "T1_GND")
			(clearance 0.10795)
			(thermal_gap 0.10795)
			(padstack
				(mode front_inner_back)
				(layer "Inner"
					(shape circle)
					(size 0.8001 0.8001)
					(clearance 0.1524)
				)
				(layer "B.Cu"
					(shape circle)
					(size 1.9939 1.9939)
					(clearance 0.10795)
				)
			)
		)
		(pad "3" thru_hole circle
			(at 2.54 2.54 90)
			(size 1.9939 1.9939)
			(drill 0.249936)
			(layers "*.Cu" "*.Mask")
			(remove_unused_layers no)
			(net "T1_GND")
			(clearance 0.10795)
			(thermal_gap 0.10795)
			(padstack
				(mode front_inner_back)
				(layer "Inner"
					(shape circle)
					(size 0.8001 0.8001)
					(clearance 0.1524)
				)
				(layer "B.Cu"
					(shape circle)
					(size 1.9939 1.9939)
					(clearance 0.10795)
				)
			)
		)
		(pad "4" thru_hole circle
			(at 0 2.54 90)
			(size 1.0033 1.0033)
			(drill 0.249936)
			(layers "*.Cu" "*.Mask")
			(remove_unused_layers no)
			(net "TDR_DIFF_85_IN1_DP")
			(clearance 0.10795)
			(thermal_gap 0.10795)
			(padstack
				(mode front_inner_back)
				(layer "Inner"
					(shape circle)
					(size 0.8001 0.8001)
					(clearance 0.1524)
				)
				(layer "B.Cu"
					(shape circle)
					(size 1.0033 1.0033)
					(clearance 0.10795)
				)
			)
		)
	)
	(footprint ""
		(layer "F.Cu")
		(at 143.895318 -114.73434)
		(property "Reference" "C2377"
			(at 0 0 0)
			(layer "F.SilkS")
			(hide yes)
			(effects
				(font
					(size 1.27 1.27)
				)
			)
		)
		(property "Value" ""
			(at 0 0 0)
			(layer "F.Fab")
			(effects
				(font
					(size 1.27 1.27)
				)
			)
		)
		(duplicate_pad_numbers_are_jumpers no)
		(fp_line
			(start -0.7874 -0.4064)
			(end 0.7874 -0.4064)
			(stroke
				(width 0.1524)
				(type default)
			)
			(layer "F.SilkS")
		)
		(fp_line
			(start -0.7874 0.4064)
			(end -0.7874 -0.4064)
			(stroke
				(width 0.1524)
				(type default)
			)
			(layer "F.SilkS")
		)
		(fp_line
			(start 0.7874 -0.4064)
			(end 0.7874 0.4064)
			(stroke
				(width 0.1524)
				(type default)
			)
			(layer "F.SilkS")
		)
		(fp_line
			(start 0.7874 0.4064)
			(end -0.7874 0.4064)
			(stroke
				(width 0.1524)
				(type default)
			)
			(layer "F.SilkS")
		)
		(fp_line
			(start -0.67945 -0.305054)
			(end -0.12065 -0.305054)
			(stroke
				(width 0.1)
				(type default)
			)
			(layer "F.Fab")
		)
		(fp_line
			(start -0.67945 0.3048)
			(end -0.67945 -0.305054)
			(stroke
				(width 0.1)
				(type default)
			)
			(layer "F.Fab")
		)
		(fp_line
			(start -0.12065 -0.305054)
			(end -0.12065 -0.2794)
			(stroke
				(width 0.1)
				(type default)
			)
			(layer "F.Fab")
		)
		(fp_line
			(start -0.12065 -0.2794)
			(end 0.12065 -0.2794)
			(stroke
				(width 0.1)
				(type default)
			)
			(layer "F.Fab")
		)
		(fp_line
			(start -0.12065 0.2794)
			(end -0.12065 0.3048)
			(stroke
				(width 0.1)
				(type default)
			)
			(layer "F.Fab")
		)
		(fp_line
			(start -0.12065 0.3048)
			(end -0.67945 0.3048)
			(stroke
				(width 0.1)
				(type default)
			)
			(layer "F.Fab")
		)
		(fp_line
			(start 0.120396 0.2794)
			(end -0.12065 0.2794)
			(stroke
				(width 0.1)
				(type default)
			)
			(layer "F.Fab")
		)
		(fp_line
			(start 0.120396 0.3048)
			(end 0.120396 0.2794)
			(stroke
				(width 0.1)
				(type default)
			)
			(layer "F.Fab")
		)
		(fp_line
			(start 0.12065 -0.3048)
			(end 0.67945 -0.3048)
			(stroke
				(width 0.1)
				(type default)
			)
			(layer "F.Fab")
		)
		(fp_line
			(start 0.12065 -0.2794)
			(end 0.12065 -0.3048)
			(stroke
				(width 0.1)
				(type default)
			)
			(layer "F.Fab")
		)
		(fp_line
			(start 0.67945 -0.3048)
			(end 0.67945 0.3048)
			(stroke
				(width 0.1)
				(type default)
			)
			(layer "F.Fab")
		)
		(fp_line
			(start 0.67945 0.3048)
			(end 0.120396 0.3048)
			(stroke
				(width 0.1)
				(type default)
			)
			(layer "F.Fab")
		)
		(pad "1" smd circle
			(at -0.40005 0)
			(size 0 0)
			(layers "F.Cu" "F.Mask" "F.Paste")
			(net "P3V3_AUX")
		)
		(pad "2" smd circle
			(at 0.40005 0)
			(size 0 0)
			(layers "F.Cu" "F.Mask" "F.Paste")
			(net "GND")
		)
	)
	(footprint ""
		(layer "F.Cu")
		(at 90.09888 -57.368948 180)
		(property "Reference" "R3025"
			(at 0 0 180)
			(layer "F.SilkS")
			(hide yes)
			(effects
				(font
					(size 1.27 1.27)
				)
			)
		)
		(property "Value" ""
			(at 0 0 180)
			(layer "F.Fab")
			(effects
				(font
					(size 1.27 1.27)
				)
			)
		)
		(duplicate_pad_numbers_are_jumpers no)
		(fp_line
			(start 0.7874 0.4064)
			(end -0.7874 0.4064)
			(stroke
				(width 0.1524)
				(type default)
			)
			(layer "F.SilkS")
		)
		(fp_line
			(start 0.7874 -0.4064)
			(end 0.7874 0.4064)
			(stroke
				(width 0.1524)
				(type default)
			)
			(layer "F.SilkS")
		)
		(fp_line
			(start -0.7874 0.4064)
			(end -0.7874 -0.4064)
			(stroke
				(width 0.1524)
				(type default)
			)
			(layer "F.SilkS")
		)
		(fp_line
			(start -0.7874 -0.4064)
			(end 0.7874 -0.4064)
			(stroke
				(width 0.1524)
				(type default)
			)
			(layer "F.SilkS")
		)
		(fp_line
			(start 0.67945 0.3048)
			(end 0.120396 0.3048)
			(stroke
				(width 0.1)
				(type default)
			)
			(layer "F.Fab")
		)
		(fp_line
			(start 0.67945 -0.3048)
			(end 0.67945 0.3048)
			(stroke
				(width 0.1)
				(type default)
			)
			(layer "F.Fab")
		)
		(fp_line
			(start 0.12065 -0.2794)
			(end 0.12065 -0.3048)
			(stroke
				(width 0.1)
				(type default)
			)
			(layer "F.Fab")
		)
		(fp_line
			(start 0.12065 -0.3048)
			(end 0.67945 -0.3048)
			(stroke
				(width 0.1)
				(type default)
			)
			(layer "F.Fab")
		)
		(fp_line
			(start 0.120396 0.3048)
			(end 0.120396 0.2794)
			(stroke
				(width 0.1)
				(type default)
			)
			(layer "F.Fab")
		)
		(fp_line
			(start 0.120396 0.2794)
			(end -0.12065 0.2794)
			(stroke
				(width 0.1)
				(type default)
			)
			(layer "F.Fab")
		)
		(fp_line
			(start -0.12065 0.3048)
			(end -0.67945 0.3048)
			(stroke
				(width 0.1)
				(type default)
			)
			(layer "F.Fab")
		)
		(fp_line
			(start -0.12065 0.2794)
			(end -0.12065 0.3048)
			(stroke
				(width 0.1)
				(type default)
			)
			(layer "F.Fab")
		)
		(fp_line
			(start -0.12065 -0.2794)
			(end 0.12065 -0.2794)
			(stroke
				(width 0.1)
				(type default)
			)
			(layer "F.Fab")
		)
		(fp_line
			(start -0.12065 -0.305054)
			(end -0.12065 -0.2794)
			(stroke
				(width 0.1)
				(type default)
			)
			(layer "F.Fab")
		)
		(fp_line
			(start -0.67945 0.3048)
			(end -0.67945 -0.305054)
			(stroke
				(width 0.1)
				(type default)
			)
			(layer "F.Fab")
		)
		(fp_line
			(start -0.67945 -0.305054)
			(end -0.12065 -0.305054)
			(stroke
				(width 0.1)
				(type default)
			)
			(layer "F.Fab")
		)
		(pad "1" smd circle
			(at -0.40005 0 180)
			(size 0 0)
			(layers "F.Cu" "F.Mask" "F.Paste")
			(net "FM_REMOTE_DEBUG_DET_R")
		)
		(pad "2" smd circle
			(at 0.40005 0 180)
			(size 0 0)
			(layers "F.Cu" "F.Mask" "F.Paste")
			(net "GND")
		)
	)
)
